(kicad_pcb
	(version 20260206)
	(generator "pcbnew")
	(generator_version "10.0")
	(general
		(thickness 1.6)
		(legacy_teardrops no)
	)
	(paper "A4")
	(title_block
		(title "dpb — 14545-sa.0730WZS0815.brd")
		(comment 1 "Honey Badger (Wiwynn) / footprints 628-635 of 1066")
	)
	(layers
		(0 "F.Cu" signal "TOP")
		(4 "In1.Cu" signal "L2GND")
		(6 "In2.Cu" signal "L3")
		(8 "In3.Cu" signal "L4VCC")
		(10 "In4.Cu" signal "L5VCC")
		(12 "In5.Cu" signal "L6")
		(14 "In6.Cu" signal "L7GND")
		(2 "B.Cu" signal "BOTTOM")
		(9 "F.Adhes" user "F.Adhesive")
		(11 "B.Adhes" user "B.Adhesive")
		(13 "F.Paste" user "Package Geometry/Pastemask Top")
		(15 "B.Paste" user "Package Geometry/Pastemask Bottom")
		(5 "F.SilkS" user "Ref Des/Silkscreen Top")
		(7 "B.SilkS" user "Ref Des/Silkscreen Bottom")
		(1 "F.Mask" user "Board Geometry/Soldermask Top")
		(3 "B.Mask" user "Board Geometry/Soldermask Bottom")
		(17 "Dwgs.User" user "User.Drawings")
		(19 "Cmts.User" user "User.Comments")
		(21 "Eco1.User" user "User.Eco1")
		(23 "Eco2.User" user "User.Eco2")
		(25 "Edge.Cuts" user "Board Geometry/Outline")
		(27 "Margin" user)
		(31 "F.CrtYd" user "Package Geometry/Place Bound Top")
		(29 "B.CrtYd" user "Package Geometry/Place Bound Bottom")
		(35 "F.Fab" user "Ref Des/Assembly Top")
		(33 "B.Fab" user "Ref Des/Assembly Bottom")
	)
	(footprint ""
		(layer "F.Cu")
		(at 210.946746 -285.7627)
		(property "Reference" "C142"
			(at 0 0 0)
			(layer "F.SilkS")
			(hide yes)
			(effects
				(font
					(size 1.27 1.27)
				)
			)
		)
		(property "Value" "SC10U25V6KX-1GP"
			(at -0.0762 -5.1308 0)
			(unlocked yes)
			(layer "F.Fab")
			(hide yes)
			(effects
				(font
					(size 1.016 1.016)
					(thickness 0.1524)
				)
			)
		)
		(property "Device Type" "C1206H71"
			(at -0.127 -6.6548 0)
			(unlocked yes)
			(layer "F.Fab")
			(hide yes)
			(effects
				(font
					(size 1.016 1.016)
					(thickness 0.1524)
				)
			)
		)
		(duplicate_pad_numbers_are_jumpers no)
		(fp_line
			(start -1.016 -2.2352)
			(end 1.016 -2.2352)
			(stroke
				(width 0.1524)
				(type default)
			)
			(layer "F.SilkS")
		)
		(fp_line
			(start -1.016 -0.8382)
			(end -1.016 -2.2352)
			(stroke
				(width 0.1524)
				(type default)
			)
			(layer "F.SilkS")
		)
		(fp_line
			(start -1.016 2.2352)
			(end -1.016 0.8382)
			(stroke
				(width 0.1524)
				(type default)
			)
			(layer "F.SilkS")
		)
		(fp_line
			(start 1.016 -2.2352)
			(end 1.016 -0.8382)
			(stroke
				(width 0.1524)
				(type default)
			)
			(layer "F.SilkS")
		)
		(fp_line
			(start 1.016 0.8382)
			(end 1.016 2.2352)
			(stroke
				(width 0.1524)
				(type default)
			)
			(layer "F.SilkS")
		)
		(fp_line
			(start 1.016 2.2352)
			(end -1.016 2.2352)
			(stroke
				(width 0.1524)
				(type default)
			)
			(layer "F.SilkS")
		)
		(fp_rect
			(start -1.0922 2.3114)
			(end 1.0922 -2.3114)
			(stroke
				(width 0)
				(type default)
			)
			(fill no)
			(layer "F.CrtYd")
		)
		(fp_poly
			(pts
				(xy 1.0922 -2.3114) (xy 1.0922 2.3114) (xy -1.0922 2.3114) (xy -1.0922 -2.3114)
			)
			(stroke
				(width 0)
				(type default)
			)
			(fill no)
			(layer "F.Fab")
		)
		(pad "1" smd rect
			(at 0 -1.397)
			(size 1.651 1.27)
			(layers "F.Cu" "F.Mask" "F.Paste")
			(net "P12V_HDD2")
		)
		(pad "2" smd rect
			(at 0 1.397)
			(size 1.651 1.27)
			(layers "F.Cu" "F.Mask" "F.Paste")
			(net "GND")
		)
	)
	(footprint ""
		(layer "F.Cu")
		(at 23.748746 -490.1057 90)
		(property "Reference" "PL6"
			(at 0 0 90)
			(layer "F.SilkS")
			(hide yes)
			(effects
				(font
					(size 1.27 1.27)
				)
			)
		)
		(property "Value" "IND-4D7UH-291-GP"
			(at -6.34492 -3.502152 90)
			(unlocked yes)
			(layer "F.Fab")
			(hide yes)
			(effects
				(font
					(size 1.016 1.016)
					(thickness 0.1524)
				)
			)
		)
		(property "Device Type" "L11102530H158"
			(at -6.3246 -5.08 90)
			(unlocked yes)
			(layer "F.Fab")
			(hide yes)
			(effects
				(font
					(size 1.016 1.016)
					(thickness 0.1524)
				)
			)
		)
		(duplicate_pad_numbers_are_jumpers no)
		(fp_line
			(start 5.2578 -6.3754)
			(end -5.2578 -6.3754)
			(stroke
				(width 0.1524)
				(type default)
			)
			(layer "F.SilkS")
		)
		(fp_line
			(start -5.2578 -6.3754)
			(end -5.2578 6.3754)
			(stroke
				(width 0.1524)
				(type default)
			)
			(layer "F.SilkS")
		)
		(fp_line
			(start 5.2578 6.3754)
			(end 5.2578 -6.3754)
			(stroke
				(width 0.1524)
				(type default)
			)
			(layer "F.SilkS")
		)
		(fp_line
			(start -5.2578 6.3754)
			(end 5.2578 6.3754)
			(stroke
				(width 0.1524)
				(type default)
			)
			(layer "F.SilkS")
		)
		(fp_rect
			(start -5.0038 5.4991)
			(end 5.0038 -5.4991)
			(stroke
				(width 0)
				(type default)
			)
			(fill no)
			(layer "F.CrtYd")
		)
		(fp_poly
			(pts
				(xy -5.5118 6.4516) (xy -5.5118 -6.4516) (xy 5.5118 -6.4516) (xy 5.5118 -0.8509) (xy 5.0038 -0.8509)
				(xy 5.0038 -5.4991) (xy -5.0038 -5.4991) (xy -5.0038 5.4991) (xy 5.0038 5.4991) (xy 5.0038 -0.8382)
				(xy 5.5118 -0.8382) (xy 5.5118 6.4516)
			)
			(stroke
				(width 0)
				(type default)
			)
			(fill no)
			(layer "F.CrtYd")
		)
		(fp_rect
			(start -5.5118 6.4516)
			(end 5.5118 -6.4516)
			(stroke
				(width 0)
				(type default)
			)
			(fill no)
			(layer "F.Fab")
		)
		(pad "1" smd rect
			(at 0 -4.435094 90)
			(size 3.2512 3.3782)
			(layers "F.Cu" "F.Mask" "F.Paste")
			(net "P5VC_LL")
		)
		(pad "2" smd rect
			(at 0 4.435094 90)
			(size 3.2512 3.3782)
			(layers "F.Cu" "F.Mask" "F.Paste")
			(net "P5VC")
		)
	)
	(footprint ""
		(layer "F.Cu")
		(at 4.699 -273.558 180)
		(property "Reference" "R542"
			(at 0 0 180)
			(layer "F.SilkS")
			(hide yes)
			(effects
				(font
					(size 1.27 1.27)
				)
			)
		)
		(property "Value" "2R2010J-1-GP"
			(at 0.254 -8.0772 180)
			(unlocked yes)
			(layer "F.Fab")
			(hide yes)
			(effects
				(font
					(size 1.016 1.016)
					(thickness 0.1524)
				)
			)
		)
		(property "Device Type" "R2010H28"
			(at 0.254 -9.6774 180)
			(unlocked yes)
			(layer "F.Fab")
			(hide yes)
			(effects
				(font
					(size 1.016 1.016)
					(thickness 0.1524)
				)
			)
		)
		(duplicate_pad_numbers_are_jumpers no)
		(fp_line
			(start 1.651 3.302)
			(end 1.651 -3.302)
			(stroke
				(width 0.1524)
				(type default)
			)
			(layer "F.SilkS")
		)
		(fp_line
			(start 1.651 -3.302)
			(end -1.651 -3.302)
			(stroke
				(width 0.1524)
				(type default)
			)
			(layer "F.SilkS")
		)
		(fp_line
			(start -1.651 3.302)
			(end 1.651 3.302)
			(stroke
				(width 0.1524)
				(type default)
			)
			(layer "F.SilkS")
		)
		(fp_line
			(start -1.651 -3.302)
			(end -1.651 3.302)
			(stroke
				(width 0.1524)
				(type default)
			)
			(layer "F.SilkS")
		)
		(fp_rect
			(start -1.7272 -3.3782)
			(end 1.7272 3.3782)
			(stroke
				(width 0)
				(type default)
			)
			(fill no)
			(layer "F.CrtYd")
		)
		(fp_poly
			(pts
				(xy 1.7272 3.3782) (xy 1.7272 -3.3782) (xy -1.7272 -3.3782) (xy -1.7272 3.3782)
			)
			(stroke
				(width 0)
				(type default)
			)
			(fill no)
			(layer "F.Fab")
		)
		(pad "1" smd rect
			(at 0 -2.3495 180)
			(size 2.794 1.143)
			(layers "F.Cu" "F.Mask" "F.Paste")
			(net "GND")
		)
		(pad "2" smd rect
			(at 0 2.3495 180)
			(size 2.794 1.143)
			(layers "F.Cu" "F.Mask" "F.Paste")
			(net "PRSNT_A")
		)
	)
	(footprint ""
		(layer "F.Cu")
		(at 211.576412 -81.006696)
		(property "Reference" "C174"
			(at 0 0 0)
			(layer "F.SilkS")
			(hide yes)
			(effects
				(font
					(size 1.27 1.27)
				)
			)
		)
		(property "Value" "SC10U25V6KX-1GP"
			(at -0.0762 -5.1308 0)
			(unlocked yes)
			(layer "F.Fab")
			(hide yes)
			(effects
				(font
					(size 1.016 1.016)
					(thickness 0.1524)
				)
			)
		)
		(property "Device Type" "C1206H71"
			(at -0.127 -6.6548 0)
			(unlocked yes)
			(layer "F.Fab")
			(hide yes)
			(effects
				(font
					(size 1.016 1.016)
					(thickness 0.1524)
				)
			)
		)
		(duplicate_pad_numbers_are_jumpers no)
		(fp_line
			(start -1.016 -2.2352)
			(end 1.016 -2.2352)
			(stroke
				(width 0.1524)
				(type default)
			)
			(layer "F.SilkS")
		)
		(fp_line
			(start -1.016 -0.8382)
			(end -1.016 -2.2352)
			(stroke
				(width 0.1524)
				(type default)
			)
			(layer "F.SilkS")
		)
		(fp_line
			(start -1.016 2.2352)
			(end -1.016 0.8382)
			(stroke
				(width 0.1524)
				(type default)
			)
			(layer "F.SilkS")
		)
		(fp_line
			(start 1.016 -2.2352)
			(end 1.016 -0.8382)
			(stroke
				(width 0.1524)
				(type default)
			)
			(layer "F.SilkS")
		)
		(fp_line
			(start 1.016 0.8382)
			(end 1.016 2.2352)
			(stroke
				(width 0.1524)
				(type default)
			)
			(layer "F.SilkS")
		)
		(fp_line
			(start 1.016 2.2352)
			(end -1.016 2.2352)
			(stroke
				(width 0.1524)
				(type default)
			)
			(layer "F.SilkS")
		)
		(fp_rect
			(start -1.0922 2.3114)
			(end 1.0922 -2.3114)
			(stroke
				(width 0)
				(type default)
			)
			(fill no)
			(layer "F.CrtYd")
		)
		(fp_poly
			(pts
				(xy 1.0922 -2.3114) (xy 1.0922 2.3114) (xy -1.0922 2.3114) (xy -1.0922 -2.3114)
			)
			(stroke
				(width 0)
				(type default)
			)
			(fill no)
			(layer "F.Fab")
		)
		(pad "1" smd rect
			(at 0 -1.397)
			(size 1.651 1.27)
			(layers "F.Cu" "F.Mask" "F.Paste")
			(net "P12V_HDD4")
		)
		(pad "2" smd rect
			(at 0 1.397)
			(size 1.651 1.27)
			(layers "F.Cu" "F.Mask" "F.Paste")
			(net "GND")
		)
	)
	(footprint ""
		(layer "F.Cu")
		(at 33.893252 -167.14851 -90)
		(property "Reference" "C233"
			(at 0 0 270)
			(layer "F.SilkS")
			(hide yes)
			(effects
				(font
					(size 1.27 1.27)
				)
			)
		)
		(property "Value" "SCD01U50V2KX-1GP"
			(at 1.1811 -2.7051 270)
			(unlocked yes)
			(layer "F.Fab")
			(hide yes)
			(effects
				(font
					(size 1.016 1.016)
					(thickness 0.1524)
				)
			)
		)
		(property "Device Type" "C402H22"
			(at 1.1811 -4.2291 270)
			(unlocked yes)
			(layer "F.Fab")
			(hide yes)
			(effects
				(font
					(size 1.016 1.016)
					(thickness 0.1524)
				)
			)
		)
		(duplicate_pad_numbers_are_jumpers no)
		(fp_rect
			(start -0.4318 0.9525)
			(end 0.4318 -0.9525)
			(stroke
				(width 0)
				(type default)
			)
			(fill no)
			(layer "F.CrtYd")
		)
		(fp_rect
			(start -0.4318 0.9525)
			(end 0.4318 -0.9525)
			(stroke
				(width 0)
				(type default)
			)
			(fill no)
			(layer "F.Fab")
		)
		(pad "1" smd custom
			(at 0 -0.4445 270)
			(size 0.1524 0.1524)
			(layers "F.Cu" "F.Mask" "F.Paste")
			(net "SAS2X28_DRIVE_RX_P_B8")
			(options
				(clearance outline)
				(anchor circle)
			)
			(primitives
				(gr_poly
					(pts
						(arc
							(start 0.3048 -0.2032)
							(mid 0.275042 -0.275042)
							(end 0.2032 -0.3048)
						)
						(arc
							(start -0.2032 -0.3048)
							(mid -0.275042 -0.275042)
							(end -0.3048 -0.2032)
						)
						(arc
							(start -0.3048 0.2032)
							(mid -0.275042 0.275042)
							(end -0.2032 0.3048)
						)
						(arc
							(start 0.2032 0.3048)
							(mid 0.275042 0.275042)
							(end 0.3048 0.2032)
						)
					)
					(width 0)
					(fill yes)
				)
			)
		)
		(pad "2" smd custom
			(at 0 0.4445 270)
			(size 0.1524 0.1524)
			(layers "F.Cu" "F.Mask" "F.Paste")
			(net "SAS2X28_B_HDD8_RX_+")
			(options
				(clearance outline)
				(anchor circle)
			)
			(primitives
				(gr_poly
					(pts
						(arc
							(start 0.3048 -0.2032)
							(mid 0.275042 -0.275042)
							(end 0.2032 -0.3048)
						)
						(arc
							(start -0.2032 -0.3048)
							(mid -0.275042 -0.275042)
							(end -0.3048 -0.2032)
						)
						(arc
							(start -0.3048 0.2032)
							(mid -0.275042 0.275042)
							(end -0.2032 0.3048)
						)
						(arc
							(start 0.2032 0.3048)
							(mid 0.275042 0.275042)
							(end 0.3048 0.2032)
						)
					)
					(width 0)
					(fill yes)
				)
			)
		)
	)
	(footprint ""
		(layer "F.Cu")
		(at 193.881756 -492.687102 -90)
		(property "Reference" "U3"
			(at 0 0 270)
			(layer "F.SilkS")
			(hide yes)
			(effects
				(font
					(size 1.27 1.27)
				)
			)
		)
		(property "Value" "74LVC1G08GW-1-GP"
			(at -2.3368 -8.6868 270)
			(unlocked yes)
			(layer "F.Fab")
			(hide yes)
			(effects
				(font
					(size 1.016 1.016)
					(thickness 0.1524)
				)
			)
		)
		(property "Device Type" "SC70-5H44"
			(at -2.3114 -10.414 270)
			(unlocked yes)
			(layer "F.Fab")
			(hide yes)
			(effects
				(font
					(size 1.016 1.016)
					(thickness 0.1524)
				)
			)
		)
		(duplicate_pad_numbers_are_jumpers no)
		(fp_line
			(start -1.27 1.7018)
			(end -1.27 -1.7018)
			(stroke
				(width 0.1524)
				(type default)
			)
			(layer "F.SilkS")
		)
		(fp_line
			(start 1.27 1.7018)
			(end -1.27 1.7018)
			(stroke
				(width 0.1524)
				(type default)
			)
			(layer "F.SilkS")
		)
		(fp_line
			(start -1.27 -1.7018)
			(end 1.27 -1.7018)
			(stroke
				(width 0.1524)
				(type default)
			)
			(layer "F.SilkS")
		)
		(fp_line
			(start 1.27 -1.7018)
			(end 1.27 1.7018)
			(stroke
				(width 0.1524)
				(type default)
			)
			(layer "F.SilkS")
		)
		(fp_line
			(start 0.6604 -1.8034)
			(end 1.3843 -1.8034)
			(stroke
				(width 0.3302)
				(type default)
			)
			(layer "F.SilkS")
		)
		(fp_line
			(start 1.3843 -1.8034)
			(end 1.3843 -1.1176)
			(stroke
				(width 0.3302)
				(type default)
			)
			(layer "F.SilkS")
		)
		(fp_rect
			(start -1.524 1.9558)
			(end 1.524 -1.9558)
			(stroke
				(width 0)
				(type default)
			)
			(fill no)
			(layer "F.CrtYd")
		)
		(fp_poly
			(pts
				(xy -1.524 -1.9558) (xy 1.524 -1.9558) (xy 1.524 1.9558) (xy -1.524 1.9558)
			)
			(stroke
				(width 0)
				(type default)
			)
			(fill no)
			(layer "F.Fab")
		)
		(pad "1" smd rect
			(at 0.65024 -0.8255 270)
			(size 0.4064 1.2192)
			(layers "F.Cu" "F.Mask" "F.Paste")
			(net "SAS_EXP_B_PWR0")
		)
		(pad "2" smd rect
			(at 0 -0.8255 270)
			(size 0.4064 1.2192)
			(layers "F.Cu" "F.Mask" "F.Paste")
			(net "SAS_EXP_A_PWR0")
		)
		(pad "3" smd rect
			(at -0.65024 -0.8255 270)
			(size 0.4064 1.2192)
			(layers "F.Cu" "F.Mask" "F.Paste")
			(net "GND")
		)
		(pad "4" smd rect
			(at -0.65024 0.8255 270)
			(size 0.4064 1.2192)
			(layers "F.Cu" "F.Mask" "F.Paste")
			(net "DRIVE_PWR0")
		)
		(pad "5" smd rect
			(at 0.65024 0.8255 270)
			(size 0.4064 1.2192)
			(layers "F.Cu" "F.Mask" "F.Paste")
			(net "P3V3")
		)
	)
	(footprint ""
		(layer "F.Cu")
		(at 215.471756 -482.120702 90)
		(property "Reference" "R106"
			(at 0 0 90)
			(layer "F.SilkS")
			(hide yes)
			(effects
				(font
					(size 1.27 1.27)
				)
			)
		)
		(property "Value" "4K7R2J-2-GP"
			(at 0.064008 -3.993896 90)
			(unlocked yes)
			(layer "F.Fab")
			(hide yes)
			(effects
				(font
					(size 1.016 1.016)
					(thickness 0.1524)
				)
			)
		)
		(property "Device Type" "R402H16"
			(at 0.064008 -5.517896 90)
			(unlocked yes)
			(layer "F.Fab")
			(hide yes)
			(effects
				(font
					(size 1.016 1.016)
					(thickness 0.1524)
				)
			)
		)
		(duplicate_pad_numbers_are_jumpers no)
		(fp_line
			(start 0.508 -0.9398)
			(end -0.508 -0.9398)
			(stroke
				(width 0.1524)
				(type default)
			)
			(layer "F.SilkS")
		)
		(fp_line
			(start -0.508 -0.9398)
			(end -0.508 0.9398)
			(stroke
				(width 0.1524)
				(type default)
			)
			(layer "F.SilkS")
		)
		(fp_rect
			(start -0.508 0.9398)
			(end 0.508 -0.9398)
			(stroke
				(width 0)
				(type default)
			)
			(fill no)
			(layer "F.CrtYd")
		)
		(fp_rect
			(start -0.508 0.9398)
			(end 0.508 -0.9398)
			(stroke
				(width 0)
				(type default)
			)
			(fill no)
			(layer "F.Fab")
		)
		(pad "1" smd custom
			(at 0 -0.4445 90)
			(size 0.1397 0.1397)
			(layers "F.Cu" "F.Mask" "F.Paste")
			(net "P3V3")
			(options
				(clearance outline)
				(anchor circle)
			)
			(primitives
				(gr_poly
					(pts
						(arc
							(start -0.1778 -0.2794)
							(mid -0.249642 -0.249642)
							(end -0.2794 -0.1778)
						)
						(arc
							(start -0.2794 0.1778)
							(mid -0.249642 0.249642)
							(end -0.1778 0.2794)
						)
						(arc
							(start 0.1778 0.2794)
							(mid 0.249642 0.249642)
							(end 0.2794 0.1778)
						)
						(arc
							(start 0.2794 -0.1778)
							(mid 0.249642 -0.249642)
							(end 0.1778 -0.2794)
						)
					)
					(width 0)
					(fill yes)
				)
			)
		)
		(pad "2" smd custom
			(at 0 0.4445 90)
			(size 0.1397 0.1397)
			(layers "F.Cu" "F.Mask" "F.Paste")
			(net "HDD_PRSNT_NET0")
			(options
				(clearance outline)
				(anchor circle)
			)
			(primitives
				(gr_poly
					(pts
						(arc
							(start -0.1778 -0.2794)
							(mid -0.249642 -0.249642)
							(end -0.2794 -0.1778)
						)
						(arc
							(start -0.2794 0.1778)
							(mid -0.249642 0.249642)
							(end -0.1778 0.2794)
						)
						(arc
							(start 0.1778 0.2794)
							(mid 0.249642 0.249642)
							(end 0.2794 0.1778)
						)
						(arc
							(start 0.2794 -0.1778)
							(mid 0.249642 -0.249642)
							(end 0.1778 -0.2794)
						)
					)
					(width 0)
					(fill yes)
				)
			)
		)
	)
	(footprint ""
		(layer "F.Cu")
		(at 188.988446 -460.282036)
		(property "Reference" "R348"
			(at 0 0 0)
			(layer "F.SilkS")
			(hide yes)
			(effects
				(font
					(size 1.27 1.27)
				)
			)
		)
		(property "Value" "4K7R2J-2-GP"
			(at 0.064008 -3.993896 0)
			(unlocked yes)
			(layer "F.Fab")
			(hide yes)
			(effects
				(font
					(size 1.016 1.016)
					(thickness 0.1524)
				)
			)
		)
		(property "Device Type" "R402H16"
			(at 0.064008 -5.517896 0)
			(unlocked yes)
			(layer "F.Fab")
			(hide yes)
			(effects
				(font
					(size 1.016 1.016)
					(thickness 0.1524)
				)
			)
		)
		(duplicate_pad_numbers_are_jumpers no)
		(fp_line
			(start -0.508 -0.9398)
			(end -0.508 0.9398)
			(stroke
				(width 0.1524)
				(type default)
			)
			(layer "F.SilkS")
		)
		(fp_line
			(start 0.508 -0.9398)
			(end -0.508 -0.9398)
			(stroke
				(width 0.1524)
				(type default)
			)
			(layer "F.SilkS")
		)
		(fp_rect
			(start -0.508 0.9398)
			(end 0.508 -0.9398)
			(stroke
				(width 0)
				(type default)
			)
			(fill no)
			(layer "F.CrtYd")
		)
		(fp_rect
			(start -0.508 0.9398)
			(end 0.508 -0.9398)
			(stroke
				(width 0)
				(type default)
			)
			(fill no)
			(layer "F.Fab")
		)
		(pad "1" smd custom
			(at 0 -0.4445)
			(size 0.1397 0.1397)
			(layers "F.Cu" "F.Mask" "F.Paste")
			(net "EEPROM_A0")
			(options
				(clearance outline)
				(anchor circle)
			)
			(primitives
				(gr_poly
					(pts
						(arc
							(start -0.1778 -0.2794)
							(mid -0.249642 -0.249642)
							(end -0.2794 -0.1778)
						)
						(arc
							(start -0.2794 0.1778)
							(mid -0.249642 0.249642)
							(end -0.1778 0.2794)
						)
						(arc
							(start 0.1778 0.2794)
							(mid 0.249642 0.249642)
							(end 0.2794 0.1778)
						)
						(arc
							(start 0.2794 -0.1778)
							(mid 0.249642 -0.249642)
							(end 0.1778 -0.2794)
						)
					)
					(width 0)
					(fill yes)
				)
			)
		)
		(pad "2" smd custom
			(at 0 0.4445)
			(size 0.1397 0.1397)
			(layers "F.Cu" "F.Mask" "F.Paste")
			(net "GND")
			(options
				(clearance outline)
				(anchor circle)
			)
			(primitives
				(gr_poly
					(pts
						(arc
							(start -0.1778 -0.2794)
							(mid -0.249642 -0.249642)
							(end -0.2794 -0.1778)
						)
						(arc
							(start -0.2794 0.1778)
							(mid -0.249642 0.249642)
							(end -0.1778 0.2794)
						)
						(arc
							(start 0.1778 0.2794)
							(mid 0.249642 0.249642)
							(end 0.2794 0.1778)
						)
						(arc
							(start 0.2794 -0.1778)
							(mid 0.249642 -0.249642)
							(end 0.1778 -0.2794)
						)
					)
					(width 0)
					(fill yes)
				)
			)
		)
	)
)
